(kicad_pcb
	(version 20260206)
	(generator "pcbnew")
	(generator_version "10.0")
	(general
		(thickness 1.6)
		(legacy_teardrops no)
	)
	(paper "A4")
	(title_block
		(title "01162023_DA0F0TEBIF0_F0T_Expander_BD_F_brd_V02_OCP.brd")
		(comment 1 "Grand Teton / footprints 3061-3061 of 9728")
	)
	(layers
		(0 "F.Cu" signal "TOP")
		(4 "In1.Cu" signal "GND")
		(6 "In2.Cu" signal "VCC")
		(8 "In3.Cu" signal "VCC1")
		(10 "In4.Cu" signal "GND1")
		(12 "In5.Cu" signal "IN1")
		(14 "In6.Cu" signal "GND2")
		(16 "In7.Cu" signal "IN2")
		(18 "In8.Cu" signal "GND3")
		(20 "In9.Cu" signal "IN3")
		(22 "In10.Cu" signal "GND4")
		(24 "In11.Cu" signal "IN4")
		(26 "In12.Cu" signal "GND5")
		(28 "In13.Cu" signal "IN5")
		(30 "In14.Cu" signal "GND6")
		(32 "In15.Cu" signal "IN6")
		(34 "In16.Cu" signal "GND7")
		(2 "B.Cu" signal "BOTTOM")
		(9 "F.Adhes" user "F.Adhesive")
		(11 "B.Adhes" user "B.Adhesive")
		(13 "F.Paste" user "Package Geometry/Pastemask Top")
		(15 "B.Paste" user "Package Geometry/Pastemask Bottom")
		(5 "F.SilkS" user "Ref Des/Silkscreen Top")
		(7 "B.SilkS" user "Ref Des/Silkscreen Bottom")
		(1 "F.Mask" user "Board Geometry/Soldermask Top")
		(3 "B.Mask" user "Board Geometry/Soldermask Bottom")
		(17 "Dwgs.User" user "User.Drawings")
		(19 "Cmts.User" user "User.Comments")
		(21 "Eco1.User" user "User.Eco1")
		(23 "Eco2.User" user "User.Eco2")
		(25 "Edge.Cuts" user "Board Geometry/Outline")
		(27 "Margin" user)
		(31 "F.CrtYd" user "Package Geometry/Place Bound Top")
		(29 "B.CrtYd" user "Package Geometry/Place Bound Bottom")
		(35 "F.Fab" user "Ref Des/Assembly Top")
		(33 "B.Fab" user "Ref Des/Assembly Bottom")
	)
	(footprint ""
		(layer "F.Cu")
		(at 452.374 -227.4316)
		(property "Reference" "U434"
			(at 6.531356 -0.596138 0)
			(unlocked yes)
			(layer "F.SilkS")
			(effects
				(font
					(size 0.7874 0.5842)
					(thickness 0.1524)
				)
				(justify left)
			)
		)
		(property "Value" ""
			(at 0 0 0)
			(layer "F.Fab")
			(effects
				(font
					(size 1.27 1.27)
				)
			)
		)
		(duplicate_pad_numbers_are_jumpers no)
		(fp_line
			(start -6.1214 0.750062)
			(end -5.1054 0.750062)
			(stroke
				(width 0.1524)
				(type default)
			)
			(layer "F.SilkS")
		)
		(fp_line
			(start -5.08 -1.75006)
			(end -5.588 -1.75006)
			(stroke
				(width 0.1524)
				(type default)
			)
			(layer "F.SilkS")
		)
		(fp_line
			(start -5.08 3.24993)
			(end -5.588 3.24993)
			(stroke
				(width 0.1524)
				(type default)
			)
			(layer "F.SilkS")
		)
		(fp_line
			(start -4.500118 -4.500118)
			(end -4.500118 -4.0386)
			(stroke
				(width 0.1524)
				(type default)
			)
			(layer "F.SilkS")
		)
		(fp_line
			(start -4.500118 4.0386)
			(end -4.500118 4.500118)
			(stroke
				(width 0.1524)
				(type default)
			)
			(layer "F.SilkS")
		)
		(fp_line
			(start -4.500118 4.500118)
			(end -4.0386 4.500118)
			(stroke
				(width 0.1524)
				(type default)
			)
			(layer "F.SilkS")
		)
		(fp_line
			(start -4.0386 -4.500118)
			(end -4.500118 -4.500118)
			(stroke
				(width 0.1524)
				(type default)
			)
			(layer "F.SilkS")
		)
		(fp_line
			(start -2.249932 5.0292)
			(end -2.249932 6.0452)
			(stroke
				(width 0.1524)
				(type default)
			)
			(layer "F.SilkS")
		)
		(fp_line
			(start -1.75006 -6.0706)
			(end -1.75006 -5.0546)
			(stroke
				(width 0.1524)
				(type default)
			)
			(layer "F.SilkS")
		)
		(fp_line
			(start 0.249936 5.0292)
			(end 0.249936 5.5372)
			(stroke
				(width 0.1524)
				(type default)
			)
			(layer "F.SilkS")
		)
		(fp_line
			(start 0.750062 -5.588)
			(end 0.750062 -5.08)
			(stroke
				(width 0.1524)
				(type default)
			)
			(layer "F.SilkS")
		)
		(fp_line
			(start 2.750058 5.0546)
			(end 2.750058 6.0706)
			(stroke
				(width 0.1524)
				(type default)
			)
			(layer "F.SilkS")
		)
		(fp_line
			(start 3.24993 -6.0706)
			(end 3.24993 -5.0546)
			(stroke
				(width 0.1524)
				(type default)
			)
			(layer "F.SilkS")
		)
		(fp_line
			(start 4.0386 4.500118)
			(end 4.500118 4.500118)
			(stroke
				(width 0.1524)
				(type default)
			)
			(layer "F.SilkS")
		)
		(fp_line
			(start 4.500118 -4.500118)
			(end 4.0386 -4.500118)
			(stroke
				(width 0.1524)
				(type default)
			)
			(layer "F.SilkS")
		)
		(fp_line
			(start 4.500118 -4.0386)
			(end 4.500118 -4.500118)
			(stroke
				(width 0.1524)
				(type default)
			)
			(layer "F.SilkS")
		)
		(fp_line
			(start 4.500118 4.500118)
			(end 4.500118 4.0386)
			(stroke
				(width 0.1524)
				(type default)
			)
			(layer "F.SilkS")
		)
		(fp_line
			(start 5.0292 0.249936)
			(end 6.0452 0.249936)
			(stroke
				(width 0.1524)
				(type default)
			)
			(layer "F.SilkS")
		)
		(fp_line
			(start 5.5372 -2.249932)
			(end 5.0292 -2.249932)
			(stroke
				(width 0.1524)
				(type default)
			)
			(layer "F.SilkS")
		)
		(fp_line
			(start 5.5372 2.750058)
			(end 5.0292 2.750058)
			(stroke
				(width 0.1524)
				(type default)
			)
			(layer "F.SilkS")
		)
		(fp_poly
			(pts
				(xy -6.442964 -3.7338) (xy -6.066028 -2.790444) (xy -5.31114 -3.639312)
			)
			(stroke
				(width 0)
				(type default)
			)
			(fill yes)
			(layer "F.SilkS")
		)
		(fp_line
			(start -6.1214 0.750062)
			(end -5.1054 0.750062)
			(stroke
				(width 0.1)
				(type default)
			)
			(layer "F.Fab")
		)
		(fp_line
			(start -5.08 -1.75006)
			(end -5.588 -1.75006)
			(stroke
				(width 0.1)
				(type default)
			)
			(layer "F.Fab")
		)
		(fp_line
			(start -5.08 3.24993)
			(end -5.588 3.24993)
			(stroke
				(width 0.1)
				(type default)
			)
			(layer "F.Fab")
		)
		(fp_line
			(start -4.500118 -4.500118)
			(end -4.500118 4.500118)
			(stroke
				(width 0.1)
				(type default)
			)
			(layer "F.Fab")
		)
		(fp_line
			(start -4.500118 4.500118)
			(end 4.500118 4.500118)
			(stroke
				(width 0.1)
				(type default)
			)
			(layer "F.Fab")
		)
		(fp_line
			(start -2.249932 5.0292)
			(end -2.249932 6.0452)
			(stroke
				(width 0.1)
				(type default)
			)
			(layer "F.Fab")
		)
		(fp_line
			(start -1.75006 -6.0706)
			(end -1.75006 -5.0546)
			(stroke
				(width 0.1)
				(type default)
			)
			(layer "F.Fab")
		)
		(fp_line
			(start 0.249936 5.0292)
			(end 0.249936 5.5372)
			(stroke
				(width 0.1)
				(type default)
			)
			(layer "F.Fab")
		)
		(fp_line
			(start 0.750062 -5.588)
			(end 0.750062 -5.08)
			(stroke
				(width 0.1)
				(type default)
			)
			(layer "F.Fab")
		)
		(fp_line
			(start 2.750058 5.0546)
			(end 2.750058 6.0706)
			(stroke
				(width 0.1)
				(type default)
			)
			(layer "F.Fab")
		)
		(fp_line
			(start 3.24993 -6.0706)
			(end 3.24993 -5.0546)
			(stroke
				(width 0.1)
				(type default)
			)
			(layer "F.Fab")
		)
		(fp_line
			(start 4.500118 -4.500118)
			(end -4.500118 -4.500118)
			(stroke
				(width 0.1)
				(type default)
			)
			(layer "F.Fab")
		)
		(fp_line
			(start 4.500118 4.500118)
			(end 4.500118 -4.500118)
			(stroke
				(width 0.1)
				(type default)
			)
			(layer "F.Fab")
		)
		(fp_line
			(start 5.0292 0.249936)
			(end 6.0452 0.249936)
			(stroke
				(width 0.1)
				(type default)
			)
			(layer "F.Fab")
		)
		(fp_line
			(start 5.5372 -2.249932)
			(end 5.0292 -2.249932)
			(stroke
				(width 0.1)
				(type default)
			)
			(layer "F.Fab")
		)
		(fp_line
			(start 5.5372 2.750058)
			(end 5.0292 2.750058)
			(stroke
				(width 0.1)
				(type default)
			)
			(layer "F.Fab")
		)
		(fp_poly
			(pts
				(xy -6.0452 -4.258056) (xy -6.0452 -3.242056) (xy -5.0292 -3.750056)
			)
			(stroke
				(width 0)
				(type default)
			)
			(fill yes)
			(layer "F.Fab")
		)
		(fp_text user "16"
			(at -6.116828 5.878068 270)
			(unlocked yes)
			(layer "F.SilkS")
			(effects
				(font
					(size 0.7874 0.5842)
					(thickness 0.1524)
				)
			)
		)
		(fp_text user "64"
			(at -4.703826 -4.99872 0)
			(unlocked yes)
			(layer "F.SilkS")
			(effects
				(font
					(size 0.7874 0.5842)
					(thickness 0.1524)
				)
			)
		)
		(fp_text user "17"
			(at -4.350004 6.070092 0)
			(unlocked yes)
			(layer "F.SilkS")
			(effects
				(font
					(size 0.7874 0.5842)
					(thickness 0.1524)
				)
			)
		)
		(fp_text user "32"
			(at 4.445 5.496052 0)
			(unlocked yes)
			(layer "F.SilkS")
			(effects
				(font
					(size 0.7874 0.5842)
					(thickness 0.1524)
				)
			)
		)
		(fp_text user "49"
			(at 5.167884 -5.369052 0)
			(unlocked yes)
			(layer "F.SilkS")
			(effects
				(font
					(size 0.7874 0.5842)
					(thickness 0.1524)
				)
			)
		)
		(fp_text user "33"
			(at 5.425948 4.318 270)
			(unlocked yes)
			(layer "F.SilkS")
			(effects
				(font
					(size 0.7874 0.5842)
					(thickness 0.1524)
				)
			)
		)
		(fp_text user "48"
			(at 6.353302 -5.121656 270)
			(unlocked yes)
			(layer "F.SilkS")
			(effects
				(font
					(size 0.7874 0.5842)
					(thickness 0.1524)
				)
			)
		)
		(fp_text user "16"
			(at -5.496052 4.318 270)
			(unlocked yes)
			(layer "F.Fab")
			(effects
				(font
					(size 0.7874 0.5842)
					(thickness 0.1524)
				)
			)
		)
		(fp_text user "64"
			(at -4.572 -5.298948 0)
			(unlocked yes)
			(layer "F.Fab")
			(effects
				(font
					(size 0.7874 0.5842)
					(thickness 0.1524)
				)
			)
		)
		(fp_text user "17"
			(at -4.572 5.496052 0)
			(unlocked yes)
			(layer "F.Fab")
			(effects
				(font
					(size 0.7874 0.5842)
					(thickness 0.1524)
				)
			)
		)
		(fp_text user "49"
			(at 4.445 -5.298948 0)
			(unlocked yes)
			(layer "F.Fab")
			(effects
				(font
					(size 0.7874 0.5842)
					(thickness 0.1524)
				)
			)
		)
		(fp_text user "32"
			(at 4.445 5.496052 0)
			(unlocked yes)
			(layer "F.Fab")
			(effects
				(font
					(size 0.7874 0.5842)
					(thickness 0.1524)
				)
			)
		)
		(fp_text user "48"
			(at 5.425948 -4.445 270)
			(unlocked yes)
			(layer "F.Fab")
			(effects
				(font
					(size 0.7874 0.5842)
					(thickness 0.1524)
				)
			)
		)
		(fp_text user "33"
			(at 5.425948 4.318 270)
			(unlocked yes)
			(layer "F.Fab")
			(effects
				(font
					(size 0.7874 0.5842)
					(thickness 0.1524)
				)
			)
		)
		(pad "1" smd circle
			(at -4.45008 -3.750056 270)
			(size 0 0)
			(layers "F.Cu" "F.Mask" "F.Paste")
			(net "UART_PEX3_SDB_CP2108_TX")
		)
		(pad "2" smd circle
			(at -4.45008 -3.24993 270)
			(size 0 0)
			(layers "F.Cu" "F.Mask" "F.Paste")
			(net "GND")
		)
		(pad "3" smd circle
			(at -4.45008 -2.750058 270)
			(size 0 0)
			(layers "F.Cu" "F.Mask" "F.Paste")
			(net "P3V3_AUX")
		)
		(pad "4" smd circle
			(at -4.45008 -2.249932 270)
			(size 0 0)
			(layers "F.Cu" "F.Mask" "F.Paste")
			(net "UART_PEX3_SDB_CP2108_RX")
		)
		(pad "5" smd circle
			(at -4.45008 -1.75006 270)
			(size 0 0)
			(layers "F.Cu" "F.Mask" "F.Paste")
			(net "Net_9287")
		)
		(pad "6" smd circle
			(at -4.45008 -1.249934 270)
			(size 0 0)
			(layers "F.Cu" "F.Mask" "F.Paste")
			(net "Net_9249")
		)
		(pad "7" smd circle
			(at -4.45008 -0.750062 270)
			(size 0 0)
			(layers "F.Cu" "F.Mask" "F.Paste")
			(net "Net_9253")
		)
		(pad "8" smd circle
			(at -4.45008 -0.249936 270)
			(size 0 0)
			(layers "F.Cu" "F.Mask" "F.Paste")
			(net "Net_9283")
		)
		(pad "9" smd circle
			(at -4.45008 0.249936 270)
			(size 0 0)
			(layers "F.Cu" "F.Mask" "F.Paste")
			(net "Net_9279")
		)
		(pad "10" smd circle
			(at -4.45008 0.750062 270)
			(size 0 0)
			(layers "F.Cu" "F.Mask" "F.Paste")
			(net "Net_9275")
		)
		(pad "11" smd circle
			(at -4.45008 1.249934 270)
			(size 0 0)
			(layers "F.Cu" "F.Mask" "F.Paste")
			(net "Net_9254")
		)
		(pad "12" smd circle
			(at -4.45008 1.75006 270)
			(size 0 0)
			(layers "F.Cu" "F.Mask" "F.Paste")
			(net "Net_9284")
		)
		(pad "13" smd circle
			(at -4.45008 2.249932 270)
			(size 0 0)
			(layers "F.Cu" "F.Mask" "F.Paste")
			(net "Net_9288")
		)
		(pad "14" smd circle
			(at -4.45008 2.750058 270)
			(size 0 0)
			(layers "F.Cu" "F.Mask" "F.Paste")
			(net "Net_9250")
		)
		(pad "15" smd circle
			(at -4.45008 3.24993 270)
			(size 0 0)
			(layers "F.Cu" "F.Mask" "F.Paste")
			(net "UART_PEX2_SDB_CP2108_TX")
		)
		(pad "16" smd circle
			(at -4.45008 3.750056 270)
			(size 0 0)
			(layers "F.Cu" "F.Mask" "F.Paste")
			(net "UART_PEX2_SDB_CP2108_RX")
		)
		(pad "17" smd circle
			(at -3.750056 4.45008)
			(size 0 0)
			(layers "F.Cu" "F.Mask" "F.Paste")
			(net "Net_9280")
		)
		(pad "18" smd circle
			(at -3.24993 4.45008)
			(size 0 0)
			(layers "F.Cu" "F.Mask" "F.Paste")
			(net "Net_9276")
		)
		(pad "19" smd circle
			(at -2.750058 4.45008)
			(size 0 0)
			(layers "F.Cu" "F.Mask" "F.Paste")
			(net "Net_9247")
		)
		(pad "20" smd circle
			(at -2.249932 4.45008)
			(size 0 0)
			(layers "F.Cu" "F.Mask" "F.Paste")
			(net "Net_9248")
		)
		(pad "21" smd circle
			(at -1.75006 4.45008)
			(size 0 0)
			(layers "F.Cu" "F.Mask" "F.Paste")
			(net "Net_9267")
		)
		(pad "22" smd circle
			(at -1.249934 4.45008)
			(size 0 0)
			(layers "F.Cu" "F.Mask" "F.Paste")
			(net "Net_9268")
		)
		(pad "23" smd circle
			(at -0.750062 4.45008)
			(size 0 0)
			(layers "F.Cu" "F.Mask" "F.Paste")
			(net "Net_9269")
		)
		(pad "24" smd circle
			(at -0.249936 4.45008)
			(size 0 0)
			(layers "F.Cu" "F.Mask" "F.Paste")
			(net "P3V3_AUX")
		)
		(pad "25" smd circle
			(at 0.249936 4.45008)
			(size 0 0)
			(layers "F.Cu" "F.Mask" "F.Paste")
			(net "GND")
		)
		(pad "26" smd circle
			(at 0.750062 4.45008)
			(size 0 0)
			(layers "F.Cu" "F.Mask" "F.Paste")
			(net "Net_9270")
		)
		(pad "27" smd circle
			(at 1.249934 4.45008)
			(size 0 0)
			(layers "F.Cu" "F.Mask" "F.Paste")
			(net "Net_9271")
		)
		(pad "28" smd circle
			(at 1.75006 4.45008)
			(size 0 0)
			(layers "F.Cu" "F.Mask" "F.Paste")
			(net "Net_9272")
		)
		(pad "29" smd circle
			(at 2.249932 4.45008)
			(size 0 0)
			(layers "F.Cu" "F.Mask" "F.Paste")
			(net "Net_9259")
		)
		(pad "30" smd circle
			(at 2.750058 4.45008)
			(size 0 0)
			(layers "F.Cu" "F.Mask" "F.Paste")
			(net "Net_9260")
		)
		(pad "31" smd circle
			(at 3.24993 4.45008)
			(size 0 0)
			(layers "F.Cu" "F.Mask" "F.Paste")
			(net "Net_9261")
		)
		(pad "32" smd circle
			(at 3.750056 4.45008)
			(size 0 0)
			(layers "F.Cu" "F.Mask" "F.Paste")
			(net "Net_9262")
		)
		(pad "33" smd circle
			(at 4.45008 3.750056 90)
			(size 0 0)
			(layers "F.Cu" "F.Mask" "F.Paste")
			(net "Net_9263")
		)
		(pad "34" smd circle
			(at 4.45008 3.24993 90)
			(size 0 0)
			(layers "F.Cu" "F.Mask" "F.Paste")
			(net "Net_9264")
		)
		(pad "35" smd circle
			(at 4.45008 2.750058 90)
			(size 0 0)
			(layers "F.Cu" "F.Mask" "F.Paste")
			(net "Net_9258")
		)
		(pad "36" smd circle
			(at 4.45008 2.249932 90)
			(size 0 0)
			(layers "F.Cu" "F.Mask" "F.Paste")
			(net "Net_9257")
		)
		(pad "37" smd circle
			(at 4.45008 1.75006 90)
			(size 0 0)
			(layers "F.Cu" "F.Mask" "F.Paste")
			(net "Net_9265")
		)
		(pad "38" smd circle
			(at 4.45008 1.249934 90)
			(size 0 0)
			(layers "F.Cu" "F.Mask" "F.Paste")
			(net "Net_9266")
		)
		(pad "39" smd circle
			(at 4.45008 0.750062 90)
			(size 0 0)
			(layers "F.Cu" "F.Mask" "F.Paste")
			(net "P3V3_AUX")
		)
		(pad "40" smd circle
			(at 4.45008 0.249936 90)
			(size 0 0)
			(layers "F.Cu" "F.Mask" "F.Paste")
			(net "Net_9273")
		)
		(pad "41" smd circle
			(at 4.45008 -0.249936 90)
			(size 0 0)
			(layers "F.Cu" "F.Mask" "F.Paste")
			(net "Net_9274")
		)
		(pad "42" smd circle
			(at 4.45008 -0.750062 90)
			(size 0 0)
			(layers "F.Cu" "F.Mask" "F.Paste")
			(net "Net_9255")
		)
		(pad "43" smd circle
			(at 4.45008 -1.249934 90)
			(size 0 0)
			(layers "F.Cu" "F.Mask" "F.Paste")
			(net "Net_9285")
		)
		(pad "44" smd circle
			(at 4.45008 -1.75006 90)
			(size 0 0)
			(layers "F.Cu" "F.Mask" "F.Paste")
			(net "Net_9281")
		)
		(pad "45" smd circle
			(at 4.45008 -2.249932 90)
			(size 0 0)
			(layers "F.Cu" "F.Mask" "F.Paste")
			(net "Net_9277")
		)
		(pad "46" smd circle
			(at 4.45008 -2.750058 90)
			(size 0 0)
			(layers "F.Cu" "F.Mask" "F.Paste")
			(net "Net_9289")
		)
		(pad "47" smd circle
			(at 4.45008 -3.24993 90)
			(size 0 0)
			(layers "F.Cu" "F.Mask" "F.Paste")
			(net "Net_9251")
		)
		(pad "48" smd circle
			(at 4.45008 -3.750056 90)
			(size 0 0)
			(layers "F.Cu" "F.Mask" "F.Paste")
			(net "UART_PEX1_SDB_CP2108_TX")
		)
		(pad "49" smd circle
			(at 3.750056 -4.45008 180)
			(size 0 0)
			(layers "F.Cu" "F.Mask" "F.Paste")
			(net "UART_PEX1_SDB_CP2108_RX")
		)
		(pad "50" smd circle
			(at 3.24993 -4.45008 180)
			(size 0 0)
			(layers "F.Cu" "F.Mask" "F.Paste")
			(net "Net_9256")
		)
		(pad "51" smd circle
			(at 2.750058 -4.45008 180)
			(size 0 0)
			(layers "F.Cu" "F.Mask" "F.Paste")
			(net "Net_9286")
		)
		(pad "52" smd circle
			(at 2.249932 -4.45008 180)
			(size 0 0)
			(layers "F.Cu" "F.Mask" "F.Paste")
			(net "Net_9282")
		)
		(pad "53" smd circle
			(at 1.75006 -4.45008 180)
			(size 0 0)
			(layers "F.Cu" "F.Mask" "F.Paste")
			(net "Net_9278")
		)
		(pad "54" smd circle
			(at 1.249934 -4.45008 180)
			(size 0 0)
			(layers "F.Cu" "F.Mask" "F.Paste")
			(net "Net_9290")
		)
		(pad "55" smd circle
			(at 0.750062 -4.45008 180)
			(size 0 0)
			(layers "F.Cu" "F.Mask" "F.Paste")
			(net "Net_9252")
		)
		(pad "56" smd circle
			(at 0.249936 -4.45008 180)
			(size 0 0)
			(layers "F.Cu" "F.Mask" "F.Paste")
			(net "UART_PEX0_SDB_CP2108_TX")
		)
		(pad "57" smd circle
			(at -0.249936 -4.45008 180)
			(size 0 0)
			(layers "F.Cu" "F.Mask" "F.Paste")
			(net "UART_PEX0_SDB_CP2108_RX")
		)
		(pad "58" smd circle
			(at -0.750062 -4.45008 180)
			(size 0 0)
			(layers "F.Cu" "F.Mask" "F.Paste")
			(net "P3V3_AUX")
		)
		(pad "59" smd circle
			(at -1.249934 -4.45008 180)
			(size 0 0)
			(layers "F.Cu" "F.Mask" "F.Paste")
			(net "GND")
		)
		(pad "60" smd circle
			(at -1.75006 -4.45008 180)
			(size 0 0)
			(layers "F.Cu" "F.Mask" "F.Paste")
			(net "P3V3_AUX")
		)
		(pad "61" smd circle
			(at -2.249932 -4.45008 180)
			(size 0 0)
			(layers "F.Cu" "F.Mask" "F.Paste")
			(net "P3V3_AUX")
		)
		(pad "62" smd circle
			(at -2.750058 -4.45008 180)
			(size 0 0)
			(layers "F.Cu" "F.Mask" "F.Paste")
			(net "USB2_CP2108_SDB_DP")
		)
		(pad "63" smd circle
			(at -3.24993 -4.45008 180)
			(size 0 0)
			(layers "F.Cu" "F.Mask" "F.Paste")
			(net "USB2_CP2108_SDB_DN")
		)
		(pad "64" smd circle
			(at -3.750056 -4.45008 180)
			(size 0 0)
			(layers "F.Cu" "F.Mask" "F.Paste")
			(net "RST_CP2108_SDB_R_N")
		)
		(pad "TH" smd rect
			(at 0 0)
			(size 4.2672 4.2672)
			(layers "F.Cu" "F.Mask" "F.Paste")
			(net "GND")
		)
		(zone
			(layer "F.Cu")
			(hatch none 0.5)
			(connect_pads
				(clearance 0)
			)
			(min_thickness 0.25)
			(keepout
				(tracks not_allowed)
				(vias allowed)
				(pads allowed)
				(copperpour not_allowed)
				(footprints allowed)
			)
			(placement
				(enabled no)
				(sheetname "")
			)
			(fill
				(thermal_gap 0.5)
				(thermal_bridge_width 0.5)
				(island_removal_mode 0)
			)
			(polygon
				(pts
					(xy 448.4116 -228.1936) (xy 448.4116 -223.4692) (xy 456.3364 -223.4692) (xy 456.3364 -231.394)
					(xy 448.4116 -231.394) (xy 448.4116 -228.219) (xy 450.1896 -228.219) (xy 450.1896 -229.616) (xy 454.5584 -229.616)
					(xy 454.5584 -225.2472) (xy 450.1896 -225.2472) (xy 450.1896 -228.1936)
				)
			)
		)
	)
)
